# T6G (Grand Teton) — schematic netlist excerpt (pin names and nets, part order shuffled) for the footprints in the layout excerpt that follows; sources: Cadence DE-HDL packaged netlist, KiCad conversion of 04192023_DAF0TMB3IC0_F0TG_MB_C_brd_V02_OCP.brd

U8007  LM4040AIM3X25NOPB  LM4040AIM3X-2.5/NOPB IC  pkg SOT23_123_2-92X1-3  page 268
  \1+\  = UV_ADR_P2V5_COMP
  \2-\  = GND
  \3\  = NC

R119  Q_RES  0 5% CHIP  pkg 0402LF  page 207 : A = SMB_SCM_2_R6_SDA ; B = PVDD11_S3_P0_PMSDA_R
R658  Q_RES  0 5% CHIP  pkg 0402LF  page 364 : A = P0V9_RETIMER_CPU1_PMSDA ; B = P0V9_RETIMER_CPU1_PMSDA_R

(kicad_pcb
	(version 20260206)
	(generator "pcbnew")
	(generator_version "10.0")
	(general
		(thickness 1.6)
		(legacy_teardrops no)
	)
	(paper "A4")
	(title_block
		(title "04192023_DAF0TMB3IC0_F0TG_MB_C_brd_V02_OCP.brd")
		(comment 1 "Grand Teton / footprints 2900-2902 of 8354")
	)
	(layers
		(0 "F.Cu" signal "TOP")
		(4 "In1.Cu" signal "GND")
		(6 "In2.Cu" signal "IN1")
		(8 "In3.Cu" signal "GND1")
		(10 "In4.Cu" signal "IN2")
		(12 "In5.Cu" signal "GND2")
		(14 "In6.Cu" signal "IN3")
		(16 "In7.Cu" signal "GND3")
		(18 "In8.Cu" signal "VCC")
		(20 "In9.Cu" signal "VCC1")
		(22 "In10.Cu" signal "GND4")
		(24 "In11.Cu" signal "IN4")
		(26 "In12.Cu" signal "GND5")
		(28 "In13.Cu" signal "IN5")
		(30 "In14.Cu" signal "GND6")
		(32 "In15.Cu" signal "IN6")
		(34 "In16.Cu" signal "GND7")
		(2 "B.Cu" signal "BOTTOM")
		(9 "F.Adhes" user "F.Adhesive")
		(11 "B.Adhes" user "B.Adhesive")
		(13 "F.Paste" user "Package Geometry/Pastemask Top")
		(15 "B.Paste" user "Package Geometry/Pastemask Bottom")
		(5 "F.SilkS" user "Ref Des/Silkscreen Top")
		(7 "B.SilkS" user "Ref Des/Silkscreen Bottom")
		(1 "F.Mask" user "Board Geometry/Soldermask Top")
		(3 "B.Mask" user "Board Geometry/Soldermask Bottom")
		(17 "Dwgs.User" user "User.Drawings")
		(19 "Cmts.User" user "User.Comments")
		(21 "Eco1.User" user "User.Eco1")
		(23 "Eco2.User" user "User.Eco2")
		(25 "Edge.Cuts" user "Board Geometry/Outline")
		(27 "Margin" user)
		(31 "F.CrtYd" user "Package Geometry/Place Bound Top")
		(29 "B.CrtYd" user "Package Geometry/Place Bound Bottom")
		(35 "F.Fab" user "Ref Des/Assembly Top")
		(33 "B.Fab" user "Ref Des/Assembly Bottom")
	)
	(footprint ""
		(layer "F.Cu")
		(at 14.892782 -404.341584 90)
		(property "Reference" "R658"
			(at 0 0 90)
			(layer "F.SilkS")
			(hide yes)
			(effects
				(font
					(size 1.27 1.27)
				)
			)
		)
		(property "Value" ""
			(at 0 0 90)
			(layer "F.Fab")
			(effects
				(font
					(size 1.27 1.27)
				)
			)
		)
		(duplicate_pad_numbers_are_jumpers no)
		(fp_line
			(start 0.7874 -0.4064)
			(end 0.7874 0.4064)
			(stroke
				(width 0.1524)
				(type default)
			)
			(layer "F.SilkS")
		)
		(fp_line
			(start -0.7874 -0.4064)
			(end 0.7874 -0.4064)
			(stroke
				(width 0.1524)
				(type default)
			)
			(layer "F.SilkS")
		)
		(fp_line
			(start 0.7874 0.4064)
			(end -0.7874 0.4064)
			(stroke
				(width 0.1524)
				(type default)
			)
			(layer "F.SilkS")
		)
		(fp_line
			(start -0.7874 0.4064)
			(end -0.7874 -0.4064)
			(stroke
				(width 0.1524)
				(type default)
			)
			(layer "F.SilkS")
		)
		(fp_line
			(start -0.12065 -0.305054)
			(end -0.12065 -0.2794)
			(stroke
				(width 0.1)
				(type default)
			)
			(layer "F.Fab")
		)
		(fp_line
			(start -0.67945 -0.305054)
			(end -0.12065 -0.305054)
			(stroke
				(width 0.1)
				(type default)
			)
			(layer "F.Fab")
		)
		(fp_line
			(start 0.67945 -0.3048)
			(end 0.67945 0.3048)
			(stroke
				(width 0.1)
				(type default)
			)
			(layer "F.Fab")
		)
		(fp_line
			(start 0.12065 -0.3048)
			(end 0.67945 -0.3048)
			(stroke
				(width 0.1)
				(type default)
			)
			(layer "F.Fab")
		)
		(fp_line
			(start 0.12065 -0.2794)
			(end 0.12065 -0.3048)
			(stroke
				(width 0.1)
				(type default)
			)
			(layer "F.Fab")
		)
		(fp_line
			(start -0.12065 -0.2794)
			(end 0.12065 -0.2794)
			(stroke
				(width 0.1)
				(type default)
			)
			(layer "F.Fab")
		)
		(fp_line
			(start 0.120396 0.2794)
			(end -0.12065 0.2794)
			(stroke
				(width 0.1)
				(type default)
			)
			(layer "F.Fab")
		)
		(fp_line
			(start -0.12065 0.2794)
			(end -0.12065 0.3048)
			(stroke
				(width 0.1)
				(type default)
			)
			(layer "F.Fab")
		)
		(fp_line
			(start 0.67945 0.3048)
			(end 0.120396 0.3048)
			(stroke
				(width 0.1)
				(type default)
			)
			(layer "F.Fab")
		)
		(fp_line
			(start 0.120396 0.3048)
			(end 0.120396 0.2794)
			(stroke
				(width 0.1)
				(type default)
			)
			(layer "F.Fab")
		)
		(fp_line
			(start -0.12065 0.3048)
			(end -0.67945 0.3048)
			(stroke
				(width 0.1)
				(type default)
			)
			(layer "F.Fab")
		)
		(fp_line
			(start -0.67945 0.3048)
			(end -0.67945 -0.305054)
			(stroke
				(width 0.1)
				(type default)
			)
			(layer "F.Fab")
		)
		(pad "1" smd circle
			(at -0.40005 0 90)
			(size 0 0)
			(layers "F.Cu" "F.Mask" "F.Paste")
			(net "P0V9_RETIMER_CPU1_PMSDA")
		)
		(pad "2" smd circle
			(at 0.40005 0 90)
			(size 0 0)
			(layers "F.Cu" "F.Mask" "F.Paste")
			(net "P0V9_RETIMER_CPU1_PMSDA_R")
		)
	)
	(footprint ""
		(layer "F.Cu")
		(at 124.968 -106.172 -90)
		(property "Reference" "U8007"
			(at 2.004314 -3.839972 90)
			(unlocked yes)
			(layer "F.SilkS")
			(effects
				(font
					(size 0.7874 0.5842)
					(thickness 0.1524)
				)
				(justify left)
			)
		)
		(property "Value" ""
			(at 0 0 270)
			(layer "F.Fab")
			(effects
				(font
					(size 1.27 1.27)
				)
			)
		)
		(duplicate_pad_numbers_are_jumpers no)
		(fp_line
			(start -1.868424 1.519936)
			(end 1.868424 1.519936)
			(stroke
				(width 0.1524)
				(type default)
			)
			(layer "F.SilkS")
		)
		(fp_line
			(start 1.868424 1.519936)
			(end 1.868424 -1.519936)
			(stroke
				(width 0.1524)
				(type default)
			)
			(layer "F.SilkS")
		)
		(fp_line
			(start -1.868424 -1.519936)
			(end -1.868424 1.519936)
			(stroke
				(width 0.1524)
				(type default)
			)
			(layer "F.SilkS")
		)
		(fp_line
			(start 1.868424 -1.519936)
			(end -1.868424 -1.519936)
			(stroke
				(width 0.1524)
				(type default)
			)
			(layer "F.SilkS")
		)
		(fp_line
			(start -0.700024 1.519936)
			(end 0.700024 1.519936)
			(stroke
				(width 0.1)
				(type default)
			)
			(layer "F.Fab")
		)
		(fp_line
			(start 0.700024 1.519936)
			(end 0.700024 -1.519936)
			(stroke
				(width 0.1)
				(type default)
			)
			(layer "F.Fab")
		)
		(fp_line
			(start -0.700024 -1.519936)
			(end -0.700024 1.519936)
			(stroke
				(width 0.1)
				(type default)
			)
			(layer "F.Fab")
		)
		(fp_line
			(start 0.700024 -1.519936)
			(end -0.700024 -1.519936)
			(stroke
				(width 0.1)
				(type default)
			)
			(layer "F.Fab")
		)
		(pad "1" smd rect
			(at -1.18491 -0.94996 180)
			(size 0.6096 1.0668)
			(layers "F.Cu" "F.Mask" "F.Paste")
			(net "UV_ADR_P2V5_COMP")
		)
		(pad "2" smd rect
			(at -1.18491 0.94996 180)
			(size 0.6096 1.0668)
			(layers "F.Cu" "F.Mask" "F.Paste")
			(net "GND")
		)
		(pad "3" smd rect
			(at 1.18491 0 180)
			(size 0.6096 1.0668)
			(layers "F.Cu" "F.Mask" "F.Paste")
			(net "Net_10850")
		)
	)
	(footprint ""
		(layer "F.Cu")
		(at 418.636958 -365.883952 180)
		(property "Reference" "R119"
			(at 0 0 180)
			(layer "F.SilkS")
			(hide yes)
			(effects
				(font
					(size 1.27 1.27)
				)
			)
		)
		(property "Value" ""
			(at 0 0 180)
			(layer "F.Fab")
			(effects
				(font
					(size 1.27 1.27)
				)
			)
		)
		(duplicate_pad_numbers_are_jumpers no)
		(fp_line
			(start 0.7874 0.4064)
			(end -0.7874 0.4064)
			(stroke
				(width 0.1524)
				(type default)
			)
			(layer "F.SilkS")
		)
		(fp_line
			(start 0.7874 -0.4064)
			(end 0.7874 0.4064)
			(stroke
				(width 0.1524)
				(type default)
			)
			(layer "F.SilkS")
		)
		(fp_line
			(start -0.7874 0.4064)
			(end -0.7874 -0.4064)
			(stroke
				(width 0.1524)
				(type default)
			)
			(layer "F.SilkS")
		)
		(fp_line
			(start -0.7874 -0.4064)
			(end 0.7874 -0.4064)
			(stroke
				(width 0.1524)
				(type default)
			)
			(layer "F.SilkS")
		)
		(fp_line
			(start 0.67945 0.3048)
			(end 0.120396 0.3048)
			(stroke
				(width 0.1)
				(type default)
			)
			(layer "F.Fab")
		)
		(fp_line
			(start 0.67945 -0.3048)
			(end 0.67945 0.3048)
			(stroke
				(width 0.1)
				(type default)
			)
			(layer "F.Fab")
		)
		(fp_line
			(start 0.12065 -0.2794)
			(end 0.12065 -0.3048)
			(stroke
				(width 0.1)
				(type default)
			)
			(layer "F.Fab")
		)
		(fp_line
			(start 0.12065 -0.3048)
			(end 0.67945 -0.3048)
			(stroke
				(width 0.1)
				(type default)
			)
			(layer "F.Fab")
		)
		(fp_line
			(start 0.120396 0.3048)
			(end 0.120396 0.2794)
			(stroke
				(width 0.1)
				(type default)
			)
			(layer "F.Fab")
		)
		(fp_line
			(start 0.120396 0.2794)
			(end -0.12065 0.2794)
			(stroke
				(width 0.1)
				(type default)
			)
			(layer "F.Fab")
		)
		(fp_line
			(start -0.12065 0.3048)
			(end -0.67945 0.3048)
			(stroke
				(width 0.1)
				(type default)
			)
			(layer "F.Fab")
		)
		(fp_line
			(start -0.12065 0.2794)
			(end -0.12065 0.3048)
			(stroke
				(width 0.1)
				(type default)
			)
			(layer "F.Fab")
		)
		(fp_line
			(start -0.12065 -0.2794)
			(end 0.12065 -0.2794)
			(stroke
				(width 0.1)
				(type default)
			)
			(layer "F.Fab")
		)
		(fp_line
			(start -0.12065 -0.305054)
			(end -0.12065 -0.2794)
			(stroke
				(width 0.1)
				(type default)
			)
			(layer "F.Fab")
		)
		(fp_line
			(start -0.67945 0.3048)
			(end -0.67945 -0.305054)
			(stroke
				(width 0.1)
				(type default)
			)
			(layer "F.Fab")
		)
		(fp_line
			(start -0.67945 -0.305054)
			(end -0.12065 -0.305054)
			(stroke
				(width 0.1)
				(type default)
			)
			(layer "F.Fab")
		)
		(pad "1" smd circle
			(at -0.40005 0 180)
			(size 0 0)
			(layers "F.Cu" "F.Mask" "F.Paste")
			(net "SMB_SCM_2_R6_SDA")
		)
		(pad "2" smd circle
			(at 0.40005 0 180)
			(size 0 0)
			(layers "F.Cu" "F.Mask" "F.Paste")
			(net "PVDD11_S3_P0_PMSDA_R")
		)
	)
)
